G04*
G04 #@! TF.GenerationSoftware,Altium Limited,Altium Designer,22.4.2 (48)*
G04*
G04 Layer_Color=7949734*
%FSLAX25Y25*%
%MOIN*%
G70*
G04*
G04 #@! TF.SameCoordinates,446674BB-F454-490D-8607-5140536C8ADF*
G04*
G04*
G04 #@! TF.FilePolarity,Positive*
G04*
G01*
G75*
%ADD10C,0.01000*%
%ADD22C,0.00900*%
%ADD177R,1.38976X0.21654*%
G36*
X671457Y-266387D02*
X643898D01*
Y-244734D01*
X671457D01*
Y-266387D01*
D02*
G37*
%LPC*%
G36*
X657088Y-251616D02*
X655783D01*
X650744Y-259167D01*
Y-251616D01*
X649523D01*
Y-261221D01*
X650842D01*
X655866Y-253684D01*
Y-261221D01*
X657088D01*
Y-251616D01*
D02*
G37*
G36*
X662723Y-251449D02*
X662542D01*
X662445Y-251463D01*
X662348D01*
X662084Y-251491D01*
X661793Y-251533D01*
X661488Y-251602D01*
X661155Y-251685D01*
X660849Y-251796D01*
X660835D01*
X660808Y-251810D01*
X660766Y-251838D01*
X660710Y-251866D01*
X660572Y-251935D01*
X660391Y-252060D01*
X660183Y-252199D01*
X659975Y-252379D01*
X659780Y-252588D01*
X659600Y-252823D01*
Y-252837D01*
X659586Y-252851D01*
X659558Y-252893D01*
X659531Y-252935D01*
X659461Y-253073D01*
X659378Y-253254D01*
X659281Y-253476D01*
X659211Y-253740D01*
X659142Y-254017D01*
X659114Y-254323D01*
X660336Y-254420D01*
Y-254406D01*
Y-254378D01*
X660350Y-254336D01*
X660363Y-254267D01*
X660405Y-254114D01*
X660461Y-253906D01*
X660544Y-253684D01*
X660669Y-253462D01*
X660821Y-253254D01*
X661016Y-253059D01*
X661044Y-253046D01*
X661113Y-252990D01*
X661252Y-252907D01*
X661432Y-252823D01*
X661668Y-252740D01*
X661946Y-252657D01*
X662293Y-252601D01*
X662681Y-252588D01*
X662876D01*
X662959Y-252601D01*
X663070Y-252615D01*
X663320Y-252643D01*
X663597Y-252698D01*
X663875Y-252768D01*
X664139Y-252879D01*
X664250Y-252948D01*
X664361Y-253018D01*
X664389Y-253032D01*
X664444Y-253087D01*
X664527Y-253184D01*
X664611Y-253295D01*
X664708Y-253448D01*
X664791Y-253615D01*
X664847Y-253809D01*
X664874Y-254031D01*
Y-254059D01*
Y-254114D01*
X664860Y-254211D01*
X664833Y-254323D01*
X664791Y-254461D01*
X664722Y-254600D01*
X664638Y-254739D01*
X664513Y-254878D01*
X664500Y-254892D01*
X664430Y-254933D01*
X664375Y-254975D01*
X664319Y-255003D01*
X664236Y-255044D01*
X664139Y-255100D01*
X664014Y-255141D01*
X663875Y-255197D01*
X663722Y-255252D01*
X663542Y-255322D01*
X663348Y-255377D01*
X663126Y-255447D01*
X662876Y-255502D01*
X662598Y-255572D01*
X662584D01*
X662529Y-255586D01*
X662445Y-255599D01*
X662348Y-255627D01*
X662223Y-255655D01*
X662071Y-255697D01*
X661918Y-255738D01*
X661751Y-255780D01*
X661390Y-255877D01*
X661044Y-255974D01*
X660877Y-256030D01*
X660724Y-256085D01*
X660585Y-256127D01*
X660474Y-256182D01*
X660461D01*
X660433Y-256196D01*
X660391Y-256224D01*
X660336Y-256252D01*
X660183Y-256335D01*
X660003Y-256446D01*
X659794Y-256599D01*
X659586Y-256765D01*
X659392Y-256960D01*
X659225Y-257168D01*
X659211Y-257196D01*
X659156Y-257265D01*
X659100Y-257390D01*
X659017Y-257557D01*
X658948Y-257751D01*
X658878Y-257987D01*
X658837Y-258250D01*
X658823Y-258528D01*
Y-258653D01*
X658850Y-258806D01*
X658878Y-259000D01*
X658934Y-259222D01*
X659003Y-259458D01*
X659114Y-259708D01*
X659267Y-259972D01*
Y-259985D01*
X659281Y-259999D01*
X659350Y-260083D01*
X659447Y-260208D01*
X659586Y-260346D01*
X659766Y-260513D01*
X659989Y-260693D01*
X660239Y-260860D01*
X660530Y-261013D01*
X660544D01*
X660572Y-261027D01*
X660613Y-261040D01*
X660669Y-261068D01*
X660752Y-261096D01*
X660849Y-261138D01*
X661071Y-261193D01*
X661335Y-261262D01*
X661654Y-261332D01*
X662001Y-261373D01*
X662376Y-261387D01*
X662598D01*
X662709Y-261373D01*
X662834D01*
X662973Y-261360D01*
X663139Y-261346D01*
X663486Y-261290D01*
X663847Y-261235D01*
X664208Y-261138D01*
X664555Y-261013D01*
X664569D01*
X664597Y-260999D01*
X664638Y-260971D01*
X664694Y-260943D01*
X664860Y-260860D01*
X665055Y-260735D01*
X665277Y-260568D01*
X665513Y-260374D01*
X665735Y-260138D01*
X665943Y-259875D01*
Y-259861D01*
X665971Y-259833D01*
X665985Y-259791D01*
X666026Y-259736D01*
X666054Y-259666D01*
X666096Y-259583D01*
X666193Y-259375D01*
X666290Y-259111D01*
X666373Y-258820D01*
X666429Y-258487D01*
X666457Y-258139D01*
X665263Y-258028D01*
Y-258042D01*
Y-258056D01*
X665249Y-258098D01*
Y-258153D01*
X665221Y-258278D01*
X665180Y-258459D01*
X665124Y-258639D01*
X665069Y-258847D01*
X664971Y-259042D01*
X664874Y-259222D01*
X664860Y-259236D01*
X664819Y-259292D01*
X664749Y-259389D01*
X664638Y-259486D01*
X664500Y-259611D01*
X664347Y-259736D01*
X664139Y-259861D01*
X663917Y-259972D01*
X663903D01*
X663889Y-259985D01*
X663847Y-259999D01*
X663806Y-260013D01*
X663667Y-260055D01*
X663486Y-260110D01*
X663264Y-260166D01*
X663015Y-260208D01*
X662737Y-260235D01*
X662431Y-260249D01*
X662307D01*
X662168Y-260235D01*
X662001Y-260222D01*
X661807Y-260194D01*
X661585Y-260166D01*
X661363Y-260110D01*
X661155Y-260041D01*
X661127Y-260027D01*
X661057Y-259999D01*
X660960Y-259944D01*
X660835Y-259888D01*
X660710Y-259791D01*
X660572Y-259694D01*
X660433Y-259583D01*
X660322Y-259444D01*
X660308Y-259430D01*
X660280Y-259375D01*
X660239Y-259305D01*
X660183Y-259194D01*
X660127Y-259083D01*
X660086Y-258945D01*
X660058Y-258792D01*
X660044Y-258625D01*
Y-258611D01*
Y-258542D01*
X660058Y-258459D01*
X660072Y-258348D01*
X660113Y-258237D01*
X660155Y-258098D01*
X660225Y-257959D01*
X660322Y-257834D01*
X660336Y-257820D01*
X660377Y-257779D01*
X660433Y-257723D01*
X660530Y-257640D01*
X660641Y-257557D01*
X660794Y-257459D01*
X660974Y-257362D01*
X661182Y-257279D01*
X661196Y-257265D01*
X661266Y-257251D01*
X661377Y-257209D01*
X661446Y-257196D01*
X661543Y-257168D01*
X661640Y-257126D01*
X661765Y-257099D01*
X661904Y-257057D01*
X662071Y-257015D01*
X662237Y-256974D01*
X662431Y-256918D01*
X662654Y-256862D01*
X662889Y-256807D01*
X662903D01*
X662945Y-256793D01*
X663015Y-256779D01*
X663098Y-256751D01*
X663209Y-256724D01*
X663334Y-256696D01*
X663611Y-256613D01*
X663917Y-256516D01*
X664236Y-256418D01*
X664513Y-256321D01*
X664638Y-256266D01*
X664749Y-256210D01*
X664763D01*
X664777Y-256196D01*
X664860Y-256141D01*
X664985Y-256071D01*
X665124Y-255960D01*
X665291Y-255835D01*
X665457Y-255683D01*
X665624Y-255502D01*
X665763Y-255308D01*
X665777Y-255280D01*
X665818Y-255211D01*
X665874Y-255100D01*
X665929Y-254961D01*
X665985Y-254781D01*
X666040Y-254572D01*
X666082Y-254350D01*
X666096Y-254114D01*
Y-254100D01*
Y-254086D01*
Y-254045D01*
Y-253989D01*
X666068Y-253851D01*
X666040Y-253670D01*
X665999Y-253462D01*
X665929Y-253226D01*
X665832Y-252990D01*
X665693Y-252754D01*
Y-252740D01*
X665679Y-252726D01*
X665610Y-252643D01*
X665513Y-252532D01*
X665388Y-252393D01*
X665221Y-252240D01*
X665013Y-252074D01*
X664763Y-251921D01*
X664486Y-251782D01*
X664472D01*
X664444Y-251769D01*
X664402Y-251755D01*
X664347Y-251727D01*
X664278Y-251699D01*
X664180Y-251671D01*
X663972Y-251616D01*
X663708Y-251560D01*
X663403Y-251505D01*
X663084Y-251463D01*
X662723Y-251449D01*
D02*
G37*
%LPD*%
D10*
X667504Y-212358D02*
X663505D01*
X665505D01*
Y-218356D01*
X661506D02*
X659507D01*
X660506D01*
Y-214358D01*
X661506D01*
X656507Y-218356D02*
Y-214358D01*
X655508D01*
X654508Y-215357D01*
Y-218356D01*
Y-215357D01*
X653509Y-214358D01*
X652509Y-215357D01*
Y-218356D01*
X647510D02*
X649510D01*
X650509Y-217357D01*
Y-215357D01*
X649510Y-214358D01*
X647510D01*
X646511Y-215357D01*
Y-216357D01*
X650509D01*
X634515Y-213358D02*
X635514Y-212358D01*
X637514D01*
X638513Y-213358D01*
Y-217357D01*
X637514Y-218356D01*
X635514D01*
X634515Y-217357D01*
X631516Y-214358D02*
X629516D01*
X628517Y-215357D01*
Y-218356D01*
X631516D01*
X632515Y-217357D01*
X631516Y-216357D01*
X628517D01*
X626517Y-214358D02*
Y-218356D01*
Y-216357D01*
X625518Y-215357D01*
X624518Y-214358D01*
X623518D01*
X616520Y-212358D02*
Y-218356D01*
X619520D01*
X620519Y-217357D01*
Y-215357D01*
X619520Y-214358D01*
X616520D01*
X608523Y-212358D02*
Y-216357D01*
X606524Y-218356D01*
X604524Y-216357D01*
Y-212358D01*
X602525D02*
X598526D01*
Y-213358D01*
X602525Y-217357D01*
Y-218356D01*
X667504Y-227954D02*
Y-221956D01*
X665505Y-223955D01*
X663505Y-221956D01*
Y-227954D01*
X661506D02*
X659507D01*
X660506D01*
Y-223955D01*
X661506D01*
X656507Y-227954D02*
Y-221956D01*
Y-225955D02*
X653509Y-223955D01*
X656507Y-225955D02*
X653509Y-227954D01*
X647510D02*
X649510D01*
X650509Y-226955D01*
Y-224955D01*
X649510Y-223955D01*
X647510D01*
X646511Y-224955D01*
Y-225955D01*
X650509D01*
X638513Y-221956D02*
Y-227954D01*
X634515D01*
X631516Y-223955D02*
X629516D01*
X628517Y-224955D01*
Y-227954D01*
X631516D01*
X632515Y-226955D01*
X631516Y-225955D01*
X628517D01*
X626517Y-227954D02*
Y-223955D01*
X625518D01*
X624518Y-224955D01*
Y-227954D01*
Y-224955D01*
X623518Y-223955D01*
X622518Y-224955D01*
Y-227954D01*
X620519Y-221956D02*
Y-227954D01*
X617520D01*
X616520Y-226955D01*
Y-225955D01*
Y-224955D01*
X617520Y-223955D01*
X620519D01*
X611522Y-227954D02*
X613521D01*
X614521Y-226955D01*
Y-224955D01*
X613521Y-223955D01*
X611522D01*
X610522Y-224955D01*
Y-225955D01*
X614521D01*
X607523Y-222956D02*
Y-223955D01*
X608523D01*
X606524D01*
X607523D01*
Y-226955D01*
X606524Y-227954D01*
X602525Y-223955D02*
X600526D01*
X599526Y-224955D01*
Y-227954D01*
X602525D01*
X603525Y-226955D01*
X602525Y-225955D01*
X599526D01*
X667504Y-237552D02*
Y-233553D01*
X665505Y-231554D01*
X663505Y-233553D01*
Y-237552D01*
Y-234553D01*
X667504D01*
X661506Y-231554D02*
Y-237552D01*
Y-234553D01*
X660506Y-233553D01*
X658507D01*
X657507Y-234553D01*
Y-237552D01*
X655508D02*
Y-233553D01*
X654508D01*
X653509Y-234553D01*
Y-237552D01*
Y-234553D01*
X652509Y-233553D01*
X651509Y-234553D01*
Y-237552D01*
X648510Y-233553D02*
X646511D01*
X645511Y-234553D01*
Y-237552D01*
X648510D01*
X649510Y-236552D01*
X648510Y-235553D01*
X645511D01*
X639513Y-231554D02*
Y-237552D01*
X642512D01*
X643512Y-236552D01*
Y-234553D01*
X642512Y-233553D01*
X639513D01*
X631516Y-231554D02*
Y-237552D01*
X628517D01*
X627517Y-236552D01*
Y-235553D01*
X628517Y-234553D01*
X631516D01*
X628517D01*
X627517Y-233553D01*
Y-232554D01*
X628517Y-231554D01*
X631516D01*
X625518Y-233553D02*
Y-236552D01*
X624518Y-237552D01*
X621519D01*
Y-238551D01*
X622518Y-239551D01*
X623518D01*
X621519Y-237552D02*
Y-233553D01*
X618520D02*
X616520D01*
X615521Y-234553D01*
Y-237552D01*
X618520D01*
X619520Y-236552D01*
X618520Y-235553D01*
X615521D01*
X611522Y-239551D02*
X610522D01*
X609523Y-238551D01*
Y-233553D01*
X612522D01*
X613521Y-234553D01*
Y-236552D01*
X612522Y-237552D01*
X609523D01*
X606524D02*
X604524D01*
X603525Y-236552D01*
Y-234553D01*
X604524Y-233553D01*
X606524D01*
X607523Y-234553D01*
Y-236552D01*
X606524Y-237552D01*
X601525Y-233553D02*
Y-236552D01*
X600526Y-237552D01*
X599526Y-236552D01*
X598526Y-237552D01*
X597527Y-236552D01*
Y-233553D01*
X595527Y-237552D02*
X593528D01*
X594527D01*
Y-233553D01*
X595527D01*
D22*
X276491Y-369099D02*
X276991Y-369599D01*
Y-370598D01*
X276491Y-371098D01*
X274492D01*
X273992Y-370598D01*
Y-369599D01*
X274492Y-369099D01*
X276991Y-366100D02*
Y-368099D01*
X275491D01*
X275991Y-367099D01*
Y-366599D01*
X275491Y-366100D01*
X274492D01*
X273992Y-366599D01*
Y-367599D01*
X274492Y-368099D01*
X276491Y-365100D02*
X276991Y-364600D01*
Y-363600D01*
X276491Y-363101D01*
X275991D01*
X275491Y-363600D01*
Y-364100D01*
Y-363600D01*
X274991Y-363101D01*
X274492D01*
X273992Y-363600D01*
Y-364600D01*
X274492Y-365100D01*
X269891Y-369099D02*
X270391Y-369599D01*
Y-370598D01*
X269891Y-371098D01*
X267892D01*
X267392Y-370598D01*
Y-369599D01*
X267892Y-369099D01*
X270391Y-366100D02*
Y-368099D01*
X268891D01*
X269391Y-367099D01*
Y-366599D01*
X268891Y-366100D01*
X267892D01*
X267392Y-366599D01*
Y-367599D01*
X267892Y-368099D01*
X267392Y-363101D02*
Y-365100D01*
X269391Y-363101D01*
X269891D01*
X270391Y-363600D01*
Y-364600D01*
X269891Y-365100D01*
X260391Y-369099D02*
X260891Y-369599D01*
Y-370598D01*
X260391Y-371098D01*
X258391D01*
X257892Y-370598D01*
Y-369599D01*
X258391Y-369099D01*
X260891Y-366100D02*
Y-368099D01*
X259391D01*
X259891Y-367099D01*
Y-366599D01*
X259391Y-366100D01*
X258391D01*
X257892Y-366599D01*
Y-367599D01*
X258391Y-368099D01*
X257892Y-365100D02*
Y-364100D01*
Y-364600D01*
X260891D01*
X260391Y-365100D01*
X253291Y-369099D02*
X253791Y-369599D01*
Y-370598D01*
X253291Y-371098D01*
X251291D01*
X250792Y-370598D01*
Y-369599D01*
X251291Y-369099D01*
X253791Y-366100D02*
Y-368099D01*
X252291D01*
X252791Y-367099D01*
Y-366599D01*
X252291Y-366100D01*
X251291D01*
X250792Y-366599D01*
Y-367599D01*
X251291Y-368099D01*
X253291Y-365100D02*
X253791Y-364600D01*
Y-363600D01*
X253291Y-363101D01*
X251291D01*
X250792Y-363600D01*
Y-364600D01*
X251291Y-365100D01*
X253291D01*
X244191Y-369099D02*
X244691Y-369599D01*
Y-370598D01*
X244191Y-371098D01*
X242192D01*
X241692Y-370598D01*
Y-369599D01*
X242192Y-369099D01*
X241692Y-366599D02*
X244691D01*
X243191Y-368099D01*
Y-366100D01*
X242192Y-365100D02*
X241692Y-364600D01*
Y-363600D01*
X242192Y-363101D01*
X244191D01*
X244691Y-363600D01*
Y-364600D01*
X244191Y-365100D01*
X243691D01*
X243191Y-364600D01*
Y-363101D01*
X237391Y-369099D02*
X237891Y-369599D01*
Y-370598D01*
X237391Y-371098D01*
X235391D01*
X234892Y-370598D01*
Y-369599D01*
X235391Y-369099D01*
X234892Y-366599D02*
X237891D01*
X236391Y-368099D01*
Y-366100D01*
X237391Y-365100D02*
X237891Y-364600D01*
Y-363600D01*
X237391Y-363101D01*
X236891D01*
X236391Y-363600D01*
X235891Y-363101D01*
X235391D01*
X234892Y-363600D01*
Y-364600D01*
X235391Y-365100D01*
X235891D01*
X236391Y-364600D01*
X236891Y-365100D01*
X237391D01*
X236391Y-364600D02*
Y-363600D01*
X225891Y-369099D02*
X226391Y-369599D01*
Y-370598D01*
X225891Y-371098D01*
X223891D01*
X223392Y-370598D01*
Y-369599D01*
X223891Y-369099D01*
X223392Y-366599D02*
X226391D01*
X224891Y-368099D01*
Y-366100D01*
X226391Y-365100D02*
Y-363101D01*
X225891D01*
X223891Y-365100D01*
X223392D01*
X218991Y-369099D02*
X219491Y-369599D01*
Y-370598D01*
X218991Y-371098D01*
X216991D01*
X216492Y-370598D01*
Y-369599D01*
X216991Y-369099D01*
X216492Y-366599D02*
X219491D01*
X217991Y-368099D01*
Y-366100D01*
X219491Y-363101D02*
X218991Y-364100D01*
X217991Y-365100D01*
X216991D01*
X216492Y-364600D01*
Y-363600D01*
X216991Y-363101D01*
X217491D01*
X217991Y-363600D01*
Y-365100D01*
X211554Y-367439D02*
X212054Y-367939D01*
Y-368939D01*
X211554Y-369439D01*
X209555D01*
X209055Y-368939D01*
Y-367939D01*
X209555Y-367439D01*
X209055Y-364940D02*
X212054D01*
X210555Y-366440D01*
Y-364440D01*
X212054Y-361441D02*
Y-363440D01*
X210555D01*
X211054Y-362441D01*
Y-361941D01*
X210555Y-361441D01*
X209555D01*
X209055Y-361941D01*
Y-362941D01*
X209555Y-363440D01*
X204566Y-367242D02*
X205066Y-367742D01*
Y-368742D01*
X204566Y-369242D01*
X202567D01*
X202067Y-368742D01*
Y-367742D01*
X202567Y-367242D01*
X202067Y-364743D02*
X205066D01*
X203567Y-366243D01*
Y-364243D01*
X202067Y-361744D02*
X205066D01*
X203567Y-363244D01*
Y-361244D01*
D177*
X575591Y-255561D02*
D03*
M02*
